# BASEBOARD_FAB2 (Tioga Pass) — schematic netlist excerpt (pin names and nets, part order shuffled) for the footprints in the layout excerpt that follows; sources: Cadence DE-HDL packaged netlist, KiCad conversion of Wiwynn_Tioga_Pass_MB.brd

C2L6  CAP_A  0.01UF 25V 10% X7R  pkg 0402V  page 173 : A = SATA6G_PCH_PCIE_UP_SATA_RXN<1> ; B = SATA6G_P1_RX_C_DN
C22W4  SC22U16V5MX-4-GP  20%  pkg SMD-BCG5  page 225 : \1\ = VR_FET_SW_P12V_STBY_PVDDQ_GHJ ; \2\ = GND
R8N2  RES  10.0K 1% CHIP  pkg 0402  page 55 : A = P3V3_STBY ; B = FM_CPU1_PKGID0

(kicad_pcb
	(version 20260206)
	(generator "pcbnew")
	(generator_version "10.0")
	(general
		(thickness 1.6)
		(legacy_teardrops no)
	)
	(paper "A4")
	(title_block
		(title "Wiwynn_Tioga_Pass_MB.brd")
		(comment 1 "Tioga Pass / footprints 2908-2910 of 4770")
	)
	(layers
		(0 "F.Cu" signal "TOP")
		(4 "In1.Cu" signal "L2GND")
		(6 "In2.Cu" signal "L3")
		(8 "In3.Cu" signal "L4GND")
		(10 "In4.Cu" signal "L5")
		(12 "In5.Cu" signal "L6GND")
		(14 "In6.Cu" signal "L7VCC")
		(16 "In7.Cu" signal "L8VCC")
		(18 "In8.Cu" signal "L9GND")
		(20 "In9.Cu" signal "L10")
		(22 "In10.Cu" signal "L11GND")
		(24 "In11.Cu" signal "L12")
		(26 "In12.Cu" signal "L13GND")
		(2 "B.Cu" signal "BOTTOM")
		(9 "F.Adhes" user "F.Adhesive")
		(11 "B.Adhes" user "B.Adhesive")
		(13 "F.Paste" user "Package Geometry/Pastemask Top")
		(15 "B.Paste" user "Package Geometry/Pastemask Bottom")
		(5 "F.SilkS" user "Ref Des/Silkscreen Top")
		(7 "B.SilkS" user "Ref Des/Silkscreen Bottom")
		(1 "F.Mask" user "Board Geometry/Soldermask Top")
		(3 "B.Mask" user "Board Geometry/Soldermask Bottom")
		(17 "Dwgs.User" user "User.Drawings")
		(19 "Cmts.User" user "User.Comments")
		(21 "Eco1.User" user "User.Eco1")
		(23 "Eco2.User" user "User.Eco2")
		(25 "Edge.Cuts" user "Board Geometry/Outline")
		(27 "Margin" user)
		(31 "F.CrtYd" user "Package Geometry/Place Bound Top")
		(29 "B.CrtYd" user "Package Geometry/Place Bound Bottom")
		(35 "F.Fab" user "Ref Des/Assembly Top")
		(33 "B.Fab" user "Ref Des/Assembly Bottom")
	)
	(footprint ""
		(layer "B.Cu")
		(at 63.2968 -92.1512 90)
		(property "Reference" "R8N2"
			(at 0 0 90)
			(layer "B.SilkS")
			(hide yes)
			(effects
				(font
					(size 1.27 1.27)
				)
				(justify mirror)
			)
		)
		(property "Value" ""
			(at 0 0 90)
			(layer "B.Fab")
			(effects
				(font
					(size 1.27 1.27)
				)
				(justify mirror)
			)
		)
		(duplicate_pad_numbers_are_jumpers no)
		(fp_poly
			(pts
				(xy 0.2794 -0.1016) (xy -0.2794 -0.1016) (xy -0.2794 0.9906) (xy 0.2794 0.9906)
			)
			(stroke
				(width 0)
				(type default)
			)
			(fill no)
			(layer "B.CrtYd")
		)
		(fp_line
			(start 0.2794 -0.1016)
			(end 0.2794 0.9906)
			(stroke
				(width 0.1)
				(type default)
			)
			(layer "B.Fab")
		)
		(fp_line
			(start -0.2794 -0.1016)
			(end 0.2794 -0.1016)
			(stroke
				(width 0.1)
				(type default)
			)
			(layer "B.Fab")
		)
		(fp_line
			(start 0.2794 0.9906)
			(end -0.2794 0.9906)
			(stroke
				(width 0.1)
				(type default)
			)
			(layer "B.Fab")
		)
		(fp_line
			(start -0.2794 0.9906)
			(end -0.2794 -0.1016)
			(stroke
				(width 0.1)
				(type default)
			)
			(layer "B.Fab")
		)
		(pad "1" smd rect
			(at 0 0 270)
			(size 0.508 0.508)
			(layers "B.Cu" "B.Mask" "B.Paste")
			(net "P3V3_STBY")
		)
		(pad "2" smd rect
			(at 0 0.889 270)
			(size 0.508 0.508)
			(layers "B.Cu" "B.Mask" "B.Paste")
			(net "FM_CPU1_PKGID0")
		)
		(zone
			(layer "B.Cu")
			(hatch none 0.5)
			(connect_pads
				(clearance 0)
			)
			(min_thickness 0.25)
			(keepout
				(tracks allowed)
				(vias not_allowed)
				(pads allowed)
				(copperpour not_allowed)
				(footprints allowed)
			)
			(placement
				(enabled no)
				(sheetname "")
			)
			(fill
				(thermal_gap 0.5)
				(thermal_bridge_width 0.5)
				(island_removal_mode 0)
			)
			(polygon
				(pts
					(xy 63.5508 -92.4052) (xy 63.5508 -91.8972) (xy 63.9318 -91.8972) (xy 63.9318 -92.4052)
				)
			)
		)
		(zone
			(layer "B.Cu")
			(hatch none 0.5)
			(connect_pads
				(clearance 0)
			)
			(min_thickness 0.25)
			(keepout
				(tracks not_allowed)
				(vias allowed)
				(pads allowed)
				(copperpour not_allowed)
				(footprints allowed)
			)
			(placement
				(enabled no)
				(sheetname "")
			)
			(fill
				(thermal_gap 0.5)
				(thermal_bridge_width 0.5)
				(island_removal_mode 0)
			)
			(polygon
				(pts
					(xy 63.9318 -92.4052) (xy 63.9318 -91.8972) (xy 63.5508 -91.8972) (xy 63.5508 -92.4052)
				)
			)
		)
	)
	(footprint ""
		(layer "B.Cu")
		(at -3.102864 -11.551412 -90)
		(property "Reference" "C22W4"
			(at 0 0 90)
			(layer "B.SilkS")
			(hide yes)
			(effects
				(font
					(size 1.27 1.27)
				)
				(justify mirror)
			)
		)
		(property "Value" "*"
			(at 0.0762 -6.2357 270)
			(unlocked yes)
			(layer "B.Fab")
			(hide yes)
			(effects
				(font
					(size 1.27 1.016)
					(thickness 0.1524)
				)
				(justify mirror)
			)
		)
		(property "Device Type" "SC22U16V5MX-4-GP_SMD-BCG5-SC22A"
			(at 0.0762 -8.2677 270)
			(unlocked yes)
			(layer "B.Fab")
			(hide yes)
			(effects
				(font
					(size 1.27 1.016)
					(thickness 0.1524)
				)
				(justify mirror)
			)
		)
		(duplicate_pad_numbers_are_jumpers no)
		(fp_line
			(start -0.635 0)
			(end 0.635 0)
			(stroke
				(width 0.508)
				(type default)
			)
			(layer "B.SilkS")
		)
		(fp_rect
			(start 0.9652 1.778)
			(end -0.9652 -1.778)
			(stroke
				(width 0)
				(type default)
			)
			(fill no)
			(layer "B.CrtYd")
		)
		(fp_poly
			(pts
				(xy 0.9652 -1.778) (xy -0.9652 -1.778) (xy -0.9652 1.778) (xy 0.9652 1.778)
			)
			(stroke
				(width 0)
				(type default)
			)
			(fill no)
			(layer "B.Fab")
		)
		(pad "1" smd rect
			(at 0 -0.9652 90)
			(size 1.397 1.143)
			(layers "B.Cu" "B.Mask" "B.Paste")
			(net "VR_FET_SW_P12V_STBY_PVDDQ_GHJ")
		)
		(pad "2" smd rect
			(at 0 0.9652 90)
			(size 1.397 1.143)
			(layers "B.Cu" "B.Mask" "B.Paste")
			(net "GND")
		)
	)
	(footprint ""
		(layer "B.Cu")
		(at 422.656 -153.924 90)
		(property "Reference" "C2L6"
			(at 0 0 90)
			(layer "B.SilkS")
			(hide yes)
			(effects
				(font
					(size 1.27 1.27)
				)
				(justify mirror)
			)
		)
		(property "Value" ""
			(at 0 0 90)
			(layer "B.Fab")
			(effects
				(font
					(size 1.27 1.27)
				)
				(justify mirror)
			)
		)
		(duplicate_pad_numbers_are_jumpers no)
		(fp_poly
			(pts
				(xy -0.3048 -0.1016) (xy -0.3048 0.9906) (xy 0.3048 0.9906) (xy 0.3048 -0.1016)
			)
			(stroke
				(width 0)
				(type default)
			)
			(fill no)
			(layer "B.CrtYd")
		)
		(fp_line
			(start 0.3048 -0.1016)
			(end 0.3048 0.9906)
			(stroke
				(width 0.1)
				(type default)
			)
			(layer "B.Fab")
		)
		(fp_line
			(start -0.3048 -0.1016)
			(end 0.3048 -0.1016)
			(stroke
				(width 0.1)
				(type default)
			)
			(layer "B.Fab")
		)
		(fp_line
			(start 0.3048 0.9906)
			(end -0.3048 0.9906)
			(stroke
				(width 0.1)
				(type default)
			)
			(layer "B.Fab")
		)
		(fp_line
			(start -0.3048 0.9906)
			(end -0.3048 -0.1016)
			(stroke
				(width 0.1)
				(type default)
			)
			(layer "B.Fab")
		)
		(pad "1" smd rect
			(at 0 0 270)
			(size 0.508 0.508)
			(layers "B.Cu" "B.Mask" "B.Paste")
			(net "SATA6G_PCH_PCIE_UP_SATA_RXN<1>")
		)
		(pad "2" smd rect
			(at 0 0.889 270)
			(size 0.508 0.508)
			(layers "B.Cu" "B.Mask" "B.Paste")
			(net "SATA6G_P1_RX_C_DN")
		)
		(zone
			(layer "B.Cu")
			(hatch none 0.5)
			(connect_pads
				(clearance 0)
			)
			(min_thickness 0.25)
			(keepout
				(tracks allowed)
				(vias not_allowed)
				(pads allowed)
				(copperpour not_allowed)
				(footprints allowed)
			)
			(placement
				(enabled no)
				(sheetname "")
			)
			(fill
				(thermal_gap 0.5)
				(thermal_bridge_width 0.5)
				(island_removal_mode 0)
			)
			(polygon
				(pts
					(xy 422.91 -154.178) (xy 422.91 -153.67) (xy 423.291 -153.67) (xy 423.291 -154.178)
				)
			)
		)
		(zone
			(layer "B.Cu")
			(hatch none 0.5)
			(connect_pads
				(clearance 0)
			)
			(min_thickness 0.25)
			(keepout
				(tracks not_allowed)
				(vias allowed)
				(pads allowed)
				(copperpour not_allowed)
				(footprints allowed)
			)
			(placement
				(enabled no)
				(sheetname "")
			)
			(fill
				(thermal_gap 0.5)
				(thermal_bridge_width 0.5)
				(island_removal_mode 0)
			)
			(polygon
				(pts
					(xy 423.291 -154.178) (xy 423.291 -153.67) (xy 422.91 -153.67) (xy 422.91 -154.178)
				)
			)
		)
	)
)
